# T6G (Grand Teton) — schematic netlist excerpt (pin names and nets, part order shuffled) for the footprints in the layout excerpt that follows; sources: Cadence DE-HDL packaged netlist, KiCad conversion of 04192023_DAF0TMB3IC0_F0TG_MB_C_brd_V02_OCP.brd

R20  Q_RES  10K 1% CHIP  pkg 0402LF  page 77 : A = P3V3_AUX ; B = SPI_CPU0_LVC3_SCM_CLK
PR432  Q_RES  5.6 1% CHIP  pkg 0402LF  page 196 : A = SW_PVDDCR_CPU0_P0_BOOT6 ; B = SW_PVDDCR_CPU0_P0_BOOT6_RC

(kicad_pcb
	(version 20260206)
	(generator "pcbnew")
	(generator_version "10.0")
	(general
		(thickness 1.6)
		(legacy_teardrops no)
	)
	(paper "A4")
	(title_block
		(title "04192023_DAF0TMB3IC0_F0TG_MB_C_brd_V02_OCP.brd")
		(comment 1 "Grand Teton / footprints 724-725 of 8354")
	)
	(layers
		(0 "F.Cu" signal "TOP")
		(4 "In1.Cu" signal "GND")
		(6 "In2.Cu" signal "IN1")
		(8 "In3.Cu" signal "GND1")
		(10 "In4.Cu" signal "IN2")
		(12 "In5.Cu" signal "GND2")
		(14 "In6.Cu" signal "IN3")
		(16 "In7.Cu" signal "GND3")
		(18 "In8.Cu" signal "VCC")
		(20 "In9.Cu" signal "VCC1")
		(22 "In10.Cu" signal "GND4")
		(24 "In11.Cu" signal "IN4")
		(26 "In12.Cu" signal "GND5")
		(28 "In13.Cu" signal "IN5")
		(30 "In14.Cu" signal "GND6")
		(32 "In15.Cu" signal "IN6")
		(34 "In16.Cu" signal "GND7")
		(2 "B.Cu" signal "BOTTOM")
		(9 "F.Adhes" user "F.Adhesive")
		(11 "B.Adhes" user "B.Adhesive")
		(13 "F.Paste" user "Package Geometry/Pastemask Top")
		(15 "B.Paste" user "Package Geometry/Pastemask Bottom")
		(5 "F.SilkS" user "Ref Des/Silkscreen Top")
		(7 "B.SilkS" user "Ref Des/Silkscreen Bottom")
		(1 "F.Mask" user "Board Geometry/Soldermask Top")
		(3 "B.Mask" user "Board Geometry/Soldermask Bottom")
		(17 "Dwgs.User" user "User.Drawings")
		(19 "Cmts.User" user "User.Comments")
		(21 "Eco1.User" user "User.Eco1")
		(23 "Eco2.User" user "User.Eco2")
		(25 "Edge.Cuts" user "Board Geometry/Outline")
		(27 "Margin" user)
		(31 "F.CrtYd" user "Package Geometry/Place Bound Top")
		(29 "B.CrtYd" user "Package Geometry/Place Bound Bottom")
		(35 "F.Fab" user "Ref Des/Assembly Top")
		(33 "B.Fab" user "Ref Des/Assembly Bottom")
	)
	(footprint ""
		(layer "F.Cu")
		(at 251.474224 -132.337556)
		(property "Reference" "R20"
			(at 0 0 0)
			(layer "F.SilkS")
			(hide yes)
			(effects
				(font
					(size 1.27 1.27)
				)
			)
		)
		(property "Value" ""
			(at 0 0 0)
			(layer "F.Fab")
			(effects
				(font
					(size 1.27 1.27)
				)
			)
		)
		(duplicate_pad_numbers_are_jumpers no)
		(fp_line
			(start -0.7874 -0.4064)
			(end 0.7874 -0.4064)
			(stroke
				(width 0.1524)
				(type default)
			)
			(layer "F.SilkS")
		)
		(fp_line
			(start -0.7874 0.4064)
			(end -0.7874 -0.4064)
			(stroke
				(width 0.1524)
				(type default)
			)
			(layer "F.SilkS")
		)
		(fp_line
			(start 0.7874 -0.4064)
			(end 0.7874 0.4064)
			(stroke
				(width 0.1524)
				(type default)
			)
			(layer "F.SilkS")
		)
		(fp_line
			(start 0.7874 0.4064)
			(end -0.7874 0.4064)
			(stroke
				(width 0.1524)
				(type default)
			)
			(layer "F.SilkS")
		)
		(fp_line
			(start -0.67945 -0.305054)
			(end -0.12065 -0.305054)
			(stroke
				(width 0.1)
				(type default)
			)
			(layer "F.Fab")
		)
		(fp_line
			(start -0.67945 0.3048)
			(end -0.67945 -0.305054)
			(stroke
				(width 0.1)
				(type default)
			)
			(layer "F.Fab")
		)
		(fp_line
			(start -0.12065 -0.305054)
			(end -0.12065 -0.2794)
			(stroke
				(width 0.1)
				(type default)
			)
			(layer "F.Fab")
		)
		(fp_line
			(start -0.12065 -0.2794)
			(end 0.12065 -0.2794)
			(stroke
				(width 0.1)
				(type default)
			)
			(layer "F.Fab")
		)
		(fp_line
			(start -0.12065 0.2794)
			(end -0.12065 0.3048)
			(stroke
				(width 0.1)
				(type default)
			)
			(layer "F.Fab")
		)
		(fp_line
			(start -0.12065 0.3048)
			(end -0.67945 0.3048)
			(stroke
				(width 0.1)
				(type default)
			)
			(layer "F.Fab")
		)
		(fp_line
			(start 0.120396 0.2794)
			(end -0.12065 0.2794)
			(stroke
				(width 0.1)
				(type default)
			)
			(layer "F.Fab")
		)
		(fp_line
			(start 0.120396 0.3048)
			(end 0.120396 0.2794)
			(stroke
				(width 0.1)
				(type default)
			)
			(layer "F.Fab")
		)
		(fp_line
			(start 0.12065 -0.3048)
			(end 0.67945 -0.3048)
			(stroke
				(width 0.1)
				(type default)
			)
			(layer "F.Fab")
		)
		(fp_line
			(start 0.12065 -0.2794)
			(end 0.12065 -0.3048)
			(stroke
				(width 0.1)
				(type default)
			)
			(layer "F.Fab")
		)
		(fp_line
			(start 0.67945 -0.3048)
			(end 0.67945 0.3048)
			(stroke
				(width 0.1)
				(type default)
			)
			(layer "F.Fab")
		)
		(fp_line
			(start 0.67945 0.3048)
			(end 0.120396 0.3048)
			(stroke
				(width 0.1)
				(type default)
			)
			(layer "F.Fab")
		)
		(pad "1" smd circle
			(at -0.40005 0)
			(size 0 0)
			(layers "F.Cu" "F.Mask" "F.Paste")
			(net "P3V3_AUX")
		)
		(pad "2" smd circle
			(at 0.40005 0)
			(size 0 0)
			(layers "F.Cu" "F.Mask" "F.Paste")
			(net "SPI_CPU0_LVC3_SCM_CLK")
		)
	)
	(footprint ""
		(layer "F.Cu")
		(at 346.968572 -156.487622 -90)
		(property "Reference" "PR432"
			(at 0 0 270)
			(layer "F.SilkS")
			(hide yes)
			(effects
				(font
					(size 1.27 1.27)
				)
			)
		)
		(property "Value" ""
			(at 0 0 270)
			(layer "F.Fab")
			(effects
				(font
					(size 1.27 1.27)
				)
			)
		)
		(duplicate_pad_numbers_are_jumpers no)
		(fp_line
			(start -0.7874 0.4064)
			(end -0.7874 -0.4064)
			(stroke
				(width 0.1524)
				(type default)
			)
			(layer "F.SilkS")
		)
		(fp_line
			(start 0.7874 0.4064)
			(end -0.7874 0.4064)
			(stroke
				(width 0.1524)
				(type default)
			)
			(layer "F.SilkS")
		)
		(fp_line
			(start -0.7874 -0.4064)
			(end 0.7874 -0.4064)
			(stroke
				(width 0.1524)
				(type default)
			)
			(layer "F.SilkS")
		)
		(fp_line
			(start 0.7874 -0.4064)
			(end 0.7874 0.4064)
			(stroke
				(width 0.1524)
				(type default)
			)
			(layer "F.SilkS")
		)
		(fp_line
			(start -0.67945 0.3048)
			(end -0.67945 -0.305054)
			(stroke
				(width 0.1)
				(type default)
			)
			(layer "F.Fab")
		)
		(fp_line
			(start -0.12065 0.3048)
			(end -0.67945 0.3048)
			(stroke
				(width 0.1)
				(type default)
			)
			(layer "F.Fab")
		)
		(fp_line
			(start 0.120396 0.3048)
			(end 0.120396 0.2794)
			(stroke
				(width 0.1)
				(type default)
			)
			(layer "F.Fab")
		)
		(fp_line
			(start 0.67945 0.3048)
			(end 0.120396 0.3048)
			(stroke
				(width 0.1)
				(type default)
			)
			(layer "F.Fab")
		)
		(fp_line
			(start -0.12065 0.2794)
			(end -0.12065 0.3048)
			(stroke
				(width 0.1)
				(type default)
			)
			(layer "F.Fab")
		)
		(fp_line
			(start 0.120396 0.2794)
			(end -0.12065 0.2794)
			(stroke
				(width 0.1)
				(type default)
			)
			(layer "F.Fab")
		)
		(fp_line
			(start -0.12065 -0.2794)
			(end 0.12065 -0.2794)
			(stroke
				(width 0.1)
				(type default)
			)
			(layer "F.Fab")
		)
		(fp_line
			(start 0.12065 -0.2794)
			(end 0.12065 -0.3048)
			(stroke
				(width 0.1)
				(type default)
			)
			(layer "F.Fab")
		)
		(fp_line
			(start 0.12065 -0.3048)
			(end 0.67945 -0.3048)
			(stroke
				(width 0.1)
				(type default)
			)
			(layer "F.Fab")
		)
		(fp_line
			(start 0.67945 -0.3048)
			(end 0.67945 0.3048)
			(stroke
				(width 0.1)
				(type default)
			)
			(layer "F.Fab")
		)
		(fp_line
			(start -0.67945 -0.305054)
			(end -0.12065 -0.305054)
			(stroke
				(width 0.1)
				(type default)
			)
			(layer "F.Fab")
		)
		(fp_line
			(start -0.12065 -0.305054)
			(end -0.12065 -0.2794)
			(stroke
				(width 0.1)
				(type default)
			)
			(layer "F.Fab")
		)
		(pad "1" smd circle
			(at -0.40005 0 270)
			(size 0 0)
			(layers "F.Cu" "F.Mask" "F.Paste")
			(net "SW_PVDDCR_CPU0_P0_BOOT6")
		)
		(pad "2" smd circle
			(at 0.40005 0 270)
			(size 0 0)
			(layers "F.Cu" "F.Mask" "F.Paste")
			(net "SW_PVDDCR_CPU0_P0_BOOT6_RC")
		)
	)
)
